# BASEBOARD_FAB2 (Tioga Pass) — schematic netlist excerpt (pin names and nets, part order shuffled) for the footprints in the layout excerpt that follows; sources: Cadence DE-HDL packaged netlist, KiCad conversion of Wiwynn_Tioga_Pass_MB.brd

R4D24  RES  42.2 1.0% EMPTY  pkg 0402  page 103 : A = CLK_100M_CPU0_BCLK1_DP ; B = GND
C6B7  CAPP  330UF 6.3V 20% POSCAP  pkg 7343LF  page 232 : A = PVPP_DEF ; B = GND
RT9  RES  0 5.0% CHIP  pkg 0603  page 209 : A = VR_PVCCIN_CPU1_PH5_BOOT ; B = VR_PVCCIN_CPU1_PH5_BOOT_R

(kicad_pcb
	(version 20260206)
	(generator "pcbnew")
	(generator_version "10.0")
	(general
		(thickness 1.6)
		(legacy_teardrops no)
	)
	(paper "A4")
	(title_block
		(title "Wiwynn_Tioga_Pass_MB.brd")
		(comment 1 "Tioga Pass / footprints 1190-1192 of 4770")
	)
	(layers
		(0 "F.Cu" signal "TOP")
		(4 "In1.Cu" signal "L2GND")
		(6 "In2.Cu" signal "L3")
		(8 "In3.Cu" signal "L4GND")
		(10 "In4.Cu" signal "L5")
		(12 "In5.Cu" signal "L6GND")
		(14 "In6.Cu" signal "L7VCC")
		(16 "In7.Cu" signal "L8VCC")
		(18 "In8.Cu" signal "L9GND")
		(20 "In9.Cu" signal "L10")
		(22 "In10.Cu" signal "L11GND")
		(24 "In11.Cu" signal "L12")
		(26 "In12.Cu" signal "L13GND")
		(2 "B.Cu" signal "BOTTOM")
		(9 "F.Adhes" user "F.Adhesive")
		(11 "B.Adhes" user "B.Adhesive")
		(13 "F.Paste" user "Package Geometry/Pastemask Top")
		(15 "B.Paste" user "Package Geometry/Pastemask Bottom")
		(5 "F.SilkS" user "Ref Des/Silkscreen Top")
		(7 "B.SilkS" user "Ref Des/Silkscreen Bottom")
		(1 "F.Mask" user "Board Geometry/Soldermask Top")
		(3 "B.Mask" user "Board Geometry/Soldermask Bottom")
		(17 "Dwgs.User" user "User.Drawings")
		(19 "Cmts.User" user "User.Comments")
		(21 "Eco1.User" user "User.Eco1")
		(23 "Eco2.User" user "User.Eco2")
		(25 "Edge.Cuts" user "Board Geometry/Outline")
		(27 "Margin" user)
		(31 "F.CrtYd" user "Package Geometry/Place Bound Top")
		(29 "B.CrtYd" user "Package Geometry/Place Bound Bottom")
		(35 "F.Fab" user "Ref Des/Assembly Top")
		(33 "B.Fab" user "Ref Des/Assembly Bottom")
	)
	(footprint ""
		(layer "F.Cu")
		(at 178.054 -77.978)
		(property "Reference" "R4D24"
			(at 0 0 0)
			(layer "F.SilkS")
			(hide yes)
			(effects
				(font
					(size 1.27 1.27)
				)
			)
		)
		(property "Value" ""
			(at 0 0 0)
			(layer "F.Fab")
			(effects
				(font
					(size 1.27 1.27)
				)
			)
		)
		(duplicate_pad_numbers_are_jumpers no)
		(fp_poly
			(pts
				(xy -0.2794 -0.1016) (xy 0.2794 -0.1016) (xy 0.2794 0.9906) (xy -0.2794 0.9906)
			)
			(stroke
				(width 0)
				(type default)
			)
			(fill no)
			(layer "F.CrtYd")
		)
		(fp_line
			(start -0.2794 -0.1016)
			(end -0.2794 0.9906)
			(stroke
				(width 0.1)
				(type default)
			)
			(layer "F.Fab")
		)
		(fp_line
			(start -0.2794 0.9906)
			(end 0.2794 0.9906)
			(stroke
				(width 0.1)
				(type default)
			)
			(layer "F.Fab")
		)
		(fp_line
			(start 0.2794 -0.1016)
			(end -0.2794 -0.1016)
			(stroke
				(width 0.1)
				(type default)
			)
			(layer "F.Fab")
		)
		(fp_line
			(start 0.2794 0.9906)
			(end 0.2794 -0.1016)
			(stroke
				(width 0.1)
				(type default)
			)
			(layer "F.Fab")
		)
		(pad "1" smd rect
			(at 0 0)
			(size 0.508 0.508)
			(layers "F.Cu" "F.Mask" "F.Paste")
			(net "CLK_100M_CPU0_BCLK1_DP")
		)
		(pad "2" smd rect
			(at 0 0.889)
			(size 0.508 0.508)
			(layers "F.Cu" "F.Mask" "F.Paste")
			(net "GND")
		)
		(zone
			(layer "F.Cu")
			(hatch none 0.5)
			(connect_pads
				(clearance 0)
			)
			(min_thickness 0.25)
			(keepout
				(tracks allowed)
				(vias not_allowed)
				(pads allowed)
				(copperpour not_allowed)
				(footprints allowed)
			)
			(placement
				(enabled no)
				(sheetname "")
			)
			(fill
				(thermal_gap 0.5)
				(thermal_bridge_width 0.5)
				(island_removal_mode 0)
			)
			(polygon
				(pts
					(xy 177.8 -77.724) (xy 178.308 -77.724) (xy 178.308 -77.343) (xy 177.8 -77.343)
				)
			)
		)
		(zone
			(layer "F.Cu")
			(hatch none 0.5)
			(connect_pads
				(clearance 0)
			)
			(min_thickness 0.25)
			(keepout
				(tracks not_allowed)
				(vias allowed)
				(pads allowed)
				(copperpour not_allowed)
				(footprints allowed)
			)
			(placement
				(enabled no)
				(sheetname "")
			)
			(fill
				(thermal_gap 0.5)
				(thermal_bridge_width 0.5)
				(island_removal_mode 0)
			)
			(polygon
				(pts
					(xy 177.8 -77.343) (xy 178.308 -77.343) (xy 178.308 -77.724) (xy 177.8 -77.724)
				)
			)
		)
	)
	(footprint ""
		(layer "F.Cu")
		(at 318.2239 -127.0508 -90)
		(property "Reference" "C6B7"
			(at 3.07467 4.8006 0)
			(unlocked yes)
			(layer "F.SilkS")
			(effects
				(font
					(size 0.7874 0.5842)
					(thickness 0.1524)
				)
				(justify left)
			)
		)
		(property "Value" ""
			(at 0 0 270)
			(layer "F.Fab")
			(effects
				(font
					(size 1.27 1.27)
				)
			)
		)
		(duplicate_pad_numbers_are_jumpers no)
		(fp_line
			(start -2.2987 7.3533)
			(end -1.7272 7.3533)
			(stroke
				(width 0.1524)
				(type default)
			)
			(layer "F.SilkS")
		)
		(fp_line
			(start 1.7272 7.3533)
			(end 2.2987 7.3533)
			(stroke
				(width 0.1524)
				(type default)
			)
			(layer "F.SilkS")
		)
		(fp_line
			(start 2.2987 7.3533)
			(end 2.2987 -0.2413)
			(stroke
				(width 0.1524)
				(type default)
			)
			(layer "F.SilkS")
		)
		(fp_line
			(start -2.032 1.524)
			(end -1.7272 1.524)
			(stroke
				(width 0.1524)
				(type default)
			)
			(layer "F.SilkS")
		)
		(fp_line
			(start 2.032 1.524)
			(end 1.7272 1.524)
			(stroke
				(width 0.1524)
				(type default)
			)
			(layer "F.SilkS")
		)
		(fp_line
			(start -2.2987 -0.2413)
			(end -2.2987 7.3533)
			(stroke
				(width 0.1524)
				(type default)
			)
			(layer "F.SilkS")
		)
		(fp_line
			(start -2.032 -0.2413)
			(end -2.2987 -0.2413)
			(stroke
				(width 0.1524)
				(type default)
			)
			(layer "F.SilkS")
		)
		(fp_line
			(start 2.2987 -0.2413)
			(end 2.032 -0.2413)
			(stroke
				(width 0.1524)
				(type default)
			)
			(layer "F.SilkS")
		)
		(fp_line
			(start -2.032 -1.524)
			(end -2.032 1.524)
			(stroke
				(width 0.1524)
				(type default)
			)
			(layer "F.SilkS")
		)
		(fp_line
			(start -1.7272 -1.524)
			(end -2.032 -1.524)
			(stroke
				(width 0.1524)
				(type default)
			)
			(layer "F.SilkS")
		)
		(fp_line
			(start 1.7272 -1.524)
			(end 2.032 -1.524)
			(stroke
				(width 0.1524)
				(type default)
			)
			(layer "F.SilkS")
		)
		(fp_line
			(start 2.032 -1.524)
			(end 2.032 1.524)
			(stroke
				(width 0.1524)
				(type default)
			)
			(layer "F.SilkS")
		)
		(fp_poly
			(pts
				(xy -2.2987 -0.2413) (xy 2.2987 -0.2413) (xy 2.2987 7.3533) (xy -2.2987 7.3533)
			)
			(stroke
				(width 0)
				(type default)
			)
			(fill no)
			(layer "F.CrtYd")
		)
		(fp_line
			(start -2.2987 7.3533)
			(end -2.2987 -0.2413)
			(stroke
				(width 0.1)
				(type default)
			)
			(layer "F.Fab")
		)
		(fp_line
			(start 2.2987 7.3533)
			(end -2.2987 7.3533)
			(stroke
				(width 0.1)
				(type default)
			)
			(layer "F.Fab")
		)
		(fp_line
			(start -2.2987 -0.2413)
			(end 2.2987 -0.2413)
			(stroke
				(width 0.1)
				(type default)
			)
			(layer "F.Fab")
		)
		(fp_line
			(start 2.2987 -0.2413)
			(end 2.2987 7.3533)
			(stroke
				(width 0.1)
				(type default)
			)
			(layer "F.Fab")
		)
		(pad "1" smd rect
			(at 0 0 270)
			(size 2.54 3.048)
			(layers "F.Cu" "F.Mask" "F.Paste")
			(net "PVPP_DEF")
		)
		(pad "2" smd rect
			(at 0 7.112 270)
			(size 2.54 3.048)
			(layers "F.Cu" "F.Mask" "F.Paste")
			(net "GND")
		)
	)
	(footprint ""
		(layer "F.Cu")
		(at 28.1305 -90.551 90)
		(property "Reference" "RT9"
			(at 1.01473 0.656336 0)
			(unlocked yes)
			(layer "F.SilkS")
			(effects
				(font
					(size 0.4064 0.254)
					(thickness 0.1524)
				)
			)
		)
		(property "Value" ""
			(at 0 0 90)
			(layer "F.Fab")
			(effects
				(font
					(size 1.27 1.27)
				)
			)
		)
		(duplicate_pad_numbers_are_jumpers no)
		(fp_poly
			(pts
				(xy -0.4953 -0.2032) (xy 0.4953 -0.2032) (xy 0.4953 1.6002) (xy -0.4953 1.6002)
			)
			(stroke
				(width 0)
				(type default)
			)
			(fill no)
			(layer "F.CrtYd")
		)
		(fp_line
			(start 0.4953 -0.2032)
			(end 0.4953 1.6002)
			(stroke
				(width 0.1)
				(type default)
			)
			(layer "F.Fab")
		)
		(fp_line
			(start -0.4953 -0.2032)
			(end 0.4953 -0.2032)
			(stroke
				(width 0.1)
				(type default)
			)
			(layer "F.Fab")
		)
		(fp_line
			(start 0.4953 1.6002)
			(end -0.4953 1.6002)
			(stroke
				(width 0.1)
				(type default)
			)
			(layer "F.Fab")
		)
		(fp_line
			(start -0.4953 1.6002)
			(end -0.4953 -0.2032)
			(stroke
				(width 0.1)
				(type default)
			)
			(layer "F.Fab")
		)
		(pad "1" smd rect
			(at 0 0 90)
			(size 0.762 0.889)
			(layers "F.Cu" "F.Mask" "F.Paste")
			(net "VR_PVCCIN_CPU1_PH5_BOOT")
		)
		(pad "2" smd rect
			(at 0 1.397 90)
			(size 0.762 0.889)
			(layers "F.Cu" "F.Mask" "F.Paste")
			(net "VR_PVCCIN_CPU1_PH5_BOOT_R")
		)
		(zone
			(layer "F.Cu")
			(hatch none 0.5)
			(connect_pads
				(clearance 0)
			)
			(min_thickness 0.25)
			(keepout
				(tracks allowed)
				(vias not_allowed)
				(pads allowed)
				(copperpour not_allowed)
				(footprints allowed)
			)
			(placement
				(enabled no)
				(sheetname "")
			)
			(fill
				(thermal_gap 0.5)
				(thermal_bridge_width 0.5)
				(island_removal_mode 0)
			)
			(polygon
				(pts
					(xy 29.083 -90.932) (xy 28.575 -90.932) (xy 28.575 -90.17) (xy 29.083 -90.17)
				)
			)
		)
		(zone
			(layer "F.Cu")
			(hatch none 0.5)
			(connect_pads
				(clearance 0)
			)
			(min_thickness 0.25)
			(keepout
				(tracks not_allowed)
				(vias allowed)
				(pads allowed)
				(copperpour not_allowed)
				(footprints allowed)
			)
			(placement
				(enabled no)
				(sheetname "")
			)
			(fill
				(thermal_gap 0.5)
				(thermal_bridge_width 0.5)
				(island_removal_mode 0)
			)
			(polygon
				(pts
					(xy 29.083 -90.17) (xy 29.083 -90.932) (xy 28.575 -90.932) (xy 28.575 -90.17)
				)
			)
		)
	)
)
